#ISCELL
  logical_power cad_note *
  *
#ISCELL
  pure_quanta quanta_title_block_c *
  *
#CELL
  pure_quanta socket4677_azif0045p001c01cs *
  page14_i1
#CELL
  pure_quanta q_res *
  page14_i100
#ISCELL
  standard offpage *
  page14_i106
#ISCELL
  standard offpage *
  page14_i108
#CELL
  pure_quanta q_res *
  page14_i109
#ISCELL
  standard offpage *
  page14_i11
#CELL
  pure_quanta q_res *
  page14_i110
#ISCELL
  standard offpage *
  page14_i111
#ISCELL
  standard offpage *
  page14_i112
#ISCELL
  standard offpage *
  page14_i114
#CELL
  pure_quanta q_res *
  page14_i115
#ISCELL
  standard offpage *
  page14_i116
#CELL
  pure_quanta q_res *
  page14_i117
#ISCELL
  standard offpage *
  page14_i118
#ISCELL
  standard offpage *
  page14_i12
#CELL
  pure_quanta q_res *
  page14_i122
#ISCELL
  standard offpage *
  page14_i123
#ISCELL
  standard offpage *
  page14_i124
#ISCELL
  standard offpage *
  page14_i125
#ISCELL
  standard offpage *
  page14_i126
#ISCELL
  standard offpage *
  page14_i127
#CELL
  pure_quanta q_res *
  page14_i128
#ISCELL
  standard offpage *
  page14_i129
#ISCELL
  standard offpage *
  page14_i13
#ISCELL
  standard offpage *
  page14_i14
#ISCELL
  standard offpage *
  page14_i15
#ISCELL
  standard offpage *
  page14_i16
#ISCELL
  standard offpage *
  page14_i17
#ISCELL
  standard offpage *
  page14_i18
#ISCELL
  standard offpage *
  page14_i19
#ISCELL
  standard offpage *
  page14_i20
#ISCELL
  standard offpage *
  page14_i21
#ISCELL
  standard offpage *
  page14_i22
#ISCELL
  standard offpage *
  page14_i23
#ISCELL
  standard offpage *
  page14_i24
#ISCELL
  standard offpage *
  page14_i25
#ISCELL
  standard offpage *
  page14_i26
#ISCELL
  standard offpage *
  page14_i27
#ISCELL
  standard offpage *
  page14_i28
#ISCELL
  standard offpage *
  page14_i32
#ISCELL
  standard offpage *
  page14_i33
#ISCELL
  standard offpage *
  page14_i34
#ISCELL
  standard offpage *
  page14_i39
#ISCELL
  standard offpage *
  page14_i40
#ISCELL
  standard offpage *
  page14_i41
#ISCELL
  standard offpage *
  page14_i42
#ISCELL
  standard offpage *
  page14_i43
#ISCELL
  standard offpage *
  page14_i44
#ISCELL
  standard offpage *
  page14_i46
#ISCELL
  standard offpage *
  page14_i5
#ISCELL
  standard offpage *
  page14_i51
#ISCELL
  standard offpage *
  page14_i52
#ISCELL
  standard offpage *
  page14_i53
#ISCELL
  standard offpage *
  page14_i54
#ISCELL
  standard offpage *
  page14_i55
#CELL
  pure_quanta q_res *
  page14_i59
#ISCELL
  standard offpage *
  page14_i6
#CELL
  pure_quanta q_res *
  page14_i60
#CELL
  pure_quanta q_res *
  page14_i61
#CELL
  pure_quanta q_res *
  page14_i62
#CELL
  pure_quanta q_res *
  page14_i63
#CELL
  pure_quanta q_res *
  page14_i64
#ISCELL
  standard offpage *
  page14_i65
#CELL
  pure_quanta q_res *
  page14_i66
#ISCELL
  standard offpage *
  page14_i67
#ISCELL
  standard offpage *
  page14_i7
#ISCELL
  standard offpage *
  page14_i76
#CELL
  pure_quanta q_res *
  page14_i78
#CELL
  pure_quanta q_res *
  page14_i79
#ISCELL
  standard offpage *
  page14_i8
#ISCELL
  standard offpage *
  page14_i80
#ISCELL
  standard offpage *
  page14_i9
#CELL
  pure_quanta q_res *
  page14_i90
#ISCELL
  standard offpage *
  page14_i91
#ISCELL
  standard offpage *
  page14_i92
#CELL
  pure_quanta q_res *
  page14_i93
#CELL
  pure_quanta q_res *
  page14_i94
#ISCELL
  logical_power universal_power *
  page14_i95
#ISCELL
  standard offpage *
  page14_i96
#ISCELL
  standard offpage *
  page14_i97
#CELL
  pure_quanta q_res *
  page14_i98
#ISCELL
  standard offpage *
  page14_i99
